# BASEBOARD_FAB2 (Tioga Pass) — schematic netlist excerpt (pin names and nets, part order shuffled) for the footprints in the layout excerpt that follows; sources: Cadence DE-HDL packaged netlist, KiCad conversion of Wiwynn_Tioga_Pass_MB.brd

EU4C2  IR354XX  IR35411 IC  pkg SM  page 204
  VOS  = PVCCIN_CPU0
  LGND  = GND
  VCC  = VR_PVCCIN_CPU0_PH5_VCIN
  VDRV  = P5V_STBY
  PGND(0)  = GND
  GL(0)  = TP_PVCCIN_CPU0_PH5_GL_0
  PGND(1)  = GND
  SW  = VR_PVCCIN_CPU0_PHASE5
  VIN(0)  = VR_FET_SW_P12V_STBY_PVCCIN_CPU0
  VIN(1)  = VR_FET_SW_P12V_STBY_PVCCIN_CPU0
  NC  = NC
  PHASE  = VR_PVCCIN_CPU0_PH5_PHASE
  BOOST  = VR_PVCCIN_CPU0_PH5_BOOT_R
  PWM  = VR_PVCCIN_CPU0_PWM5
  EN  = P5V_STBY
  TOUT_FLT  = A_TSENSE_PVCCIN_CPU0
  OCSET  = VR_PVCCIN_CPU0_PH5_OCSET
  IOUT  = ISENSE_PVCCIN_CPU0_PH5_IMON
  REFIN  = VR_PVCCIN_CPU0_AIREF5
  PGND(2)  = GND
  GL(1)  = TP_PVCCIN_CPU0_PH5_GL_1

(kicad_pcb
	(version 20260206)
	(generator "pcbnew")
	(generator_version "10.0")
	(general
		(thickness 1.6)
		(legacy_teardrops no)
	)
	(paper "A4")
	(title_block
		(title "Wiwynn_Tioga_Pass_MB.brd")
		(comment 1 "Tioga Pass / footprints 1442-1442 of 4770")
	)
	(layers
		(0 "F.Cu" signal "TOP")
		(4 "In1.Cu" signal "L2GND")
		(6 "In2.Cu" signal "L3")
		(8 "In3.Cu" signal "L4GND")
		(10 "In4.Cu" signal "L5")
		(12 "In5.Cu" signal "L6GND")
		(14 "In6.Cu" signal "L7VCC")
		(16 "In7.Cu" signal "L8VCC")
		(18 "In8.Cu" signal "L9GND")
		(20 "In9.Cu" signal "L10")
		(22 "In10.Cu" signal "L11GND")
		(24 "In11.Cu" signal "L12")
		(26 "In12.Cu" signal "L13GND")
		(2 "B.Cu" signal "BOTTOM")
		(9 "F.Adhes" user "F.Adhesive")
		(11 "B.Adhes" user "B.Adhesive")
		(13 "F.Paste" user "Package Geometry/Pastemask Top")
		(15 "B.Paste" user "Package Geometry/Pastemask Bottom")
		(5 "F.SilkS" user "Ref Des/Silkscreen Top")
		(7 "B.SilkS" user "Ref Des/Silkscreen Bottom")
		(1 "F.Mask" user "Board Geometry/Soldermask Top")
		(3 "B.Mask" user "Board Geometry/Soldermask Bottom")
		(17 "Dwgs.User" user "User.Drawings")
		(19 "Cmts.User" user "User.Comments")
		(21 "Eco1.User" user "User.Eco1")
		(23 "Eco2.User" user "User.Eco2")
		(25 "Edge.Cuts" user "Board Geometry/Outline")
		(27 "Margin" user)
		(31 "F.CrtYd" user "Package Geometry/Place Bound Top")
		(29 "B.CrtYd" user "Package Geometry/Place Bound Bottom")
		(35 "F.Fab" user "Ref Des/Assembly Top")
		(33 "B.Fab" user "Ref Des/Assembly Bottom")
	)
	(footprint ""
		(layer "F.Cu")
		(at 198.925434 -89.551764 90)
		(property "Reference" "EU4C2"
			(at 3.309366 -1.618234 0)
			(unlocked yes)
			(layer "F.SilkS")
			(effects
				(font
					(size 0.7874 0.5842)
					(thickness 0.1524)
				)
			)
		)
		(property "Value" ""
			(at 0 0 90)
			(layer "F.Fab")
			(effects
				(font
					(size 1.27 1.27)
				)
			)
		)
		(duplicate_pad_numbers_are_jumpers no)
		(fp_line
			(start 2.9718 -3.5052)
			(end 2.9718 3.429)
			(stroke
				(width 0.1524)
				(type default)
			)
			(layer "F.SilkS")
		)
		(fp_line
			(start -3.0099 -3.5052)
			(end 2.9718 -3.5052)
			(stroke
				(width 0.1524)
				(type default)
			)
			(layer "F.SilkS")
		)
		(fp_line
			(start 2.9718 3.429)
			(end -3.0099 3.429)
			(stroke
				(width 0.1524)
				(type default)
			)
			(layer "F.SilkS")
		)
		(fp_line
			(start -3.0099 3.429)
			(end -3.0099 -3.5052)
			(stroke
				(width 0.1524)
				(type default)
			)
			(layer "F.SilkS")
		)
		(fp_circle
			(center -3.373374 -3.160522)
			(end -3.373374 -3.033522)
			(stroke
				(width 0.254)
				(type default)
			)
			(fill no)
			(layer "F.SilkS")
		)
		(fp_poly
			(pts
				(xy -2.9972 -3.4925) (xy -2.9972 -2.6924) (xy -2.1971 -3.4925)
			)
			(stroke
				(width 0)
				(type default)
			)
			(fill yes)
			(layer "F.SilkS")
		)
		(fp_poly
			(pts
				(xy -2.549906 -3.050032) (xy -2.549906 3.050032) (xy 2.549906 3.050032) (xy 2.549906 -3.050032)
			)
			(stroke
				(width 0)
				(type default)
			)
			(fill no)
			(layer "F.CrtYd")
		)
		(fp_line
			(start 2.549906 -3.050032)
			(end 2.549906 3.050032)
			(stroke
				(width 0.1)
				(type default)
			)
			(layer "F.Fab")
		)
		(fp_line
			(start -2.549906 -3.050032)
			(end 2.549906 -3.050032)
			(stroke
				(width 0.1)
				(type default)
			)
			(layer "F.Fab")
		)
		(fp_line
			(start 2.549906 3.050032)
			(end -2.549906 3.050032)
			(stroke
				(width 0.1)
				(type default)
			)
			(layer "F.Fab")
		)
		(fp_line
			(start -2.549906 3.050032)
			(end -2.549906 -3.050032)
			(stroke
				(width 0.1)
				(type default)
			)
			(layer "F.Fab")
		)
		(fp_circle
			(center -3.057398 -2.678684)
			(end -3.057398 -2.551684)
			(stroke
				(width 0.254)
				(type default)
			)
			(fill no)
			(layer "F.Fab")
		)
		(pad "1" smd rect
			(at -2.39522 -2.279904 90)
			(size 0.7112 0.254)
			(layers "F.Cu" "F.Mask" "F.Paste")
			(net "PVCCIN_CPU0")
		)
		(pad "2" smd rect
			(at -2.39522 -1.83007 90)
			(size 0.7112 0.254)
			(layers "F.Cu" "F.Mask" "F.Paste")
			(net "GND")
		)
		(pad "3" smd rect
			(at -2.39522 -1.379982 90)
			(size 0.7112 0.254)
			(layers "F.Cu" "F.Mask" "F.Paste")
			(net "VR_PVCCIN_CPU0_PH5_VCIN")
		)
		(pad "4" smd rect
			(at -2.39522 -0.929894 90)
			(size 0.7112 0.254)
			(layers "F.Cu" "F.Mask" "F.Paste")
			(net "P5V_STBY")
		)
		(pad "5" smd rect
			(at -2.39522 -0.48006 90)
			(size 0.7112 0.254)
			(layers "F.Cu" "F.Mask" "F.Paste")
			(net "GND")
		)
		(pad "6" smd rect
			(at -2.39522 -0.029972 90)
			(size 0.7112 0.254)
			(layers "F.Cu" "F.Mask" "F.Paste")
			(net "TP_PVCCIN_CPU0_PH5_GL_0")
		)
		(pad "7" smd custom
			(at 0.016764 1.145032 90)
			(size 0.53975 0.53975)
			(layers "F.Cu" "F.Mask" "F.Paste")
			(net "GND")
			(options
				(clearance outline)
				(anchor circle)
			)
			(primitives
				(gr_poly
					(pts
						(xy -2.7051 1.0795) (xy -2.7051 -0.3683) (xy -0.9271 -0.3683) (xy -0.9271 -1.0795) (xy 2.7051 -1.0795)
						(xy 2.7051 1.0795)
					)
					(width 0)
					(fill yes)
				)
			)
		)
		(pad "10" smd rect
			(at -0.008382 2.874772 90)
			(size 4.3434 0.6096)
			(layers "F.Cu" "F.Mask" "F.Paste")
			(net "VR_PVCCIN_CPU0_PHASE5")
		)
		(pad "25" smd rect
			(at 1.548384 -1.283208 90)
			(size 2.3368 2.0066)
			(layers "F.Cu" "F.Mask" "F.Paste")
			(net "VR_FET_SW_P12V_STBY_PVCCIN_CPU0")
		)
		(pad "30" smd rect
			(at 2.050034 -2.895092 90)
			(size 0.254 0.7112)
			(layers "F.Cu" "F.Mask" "F.Paste")
			(net "VR_FET_SW_P12V_STBY_PVCCIN_CPU0")
		)
		(pad "31" smd rect
			(at 1.599946 -2.895092 90)
			(size 0.254 0.7112)
			(layers "F.Cu" "F.Mask" "F.Paste")
			(net "Net_365")
		)
		(pad "32" smd rect
			(at 1.150112 -2.895092 90)
			(size 0.254 0.7112)
			(layers "F.Cu" "F.Mask" "F.Paste")
			(net "VR_PVCCIN_CPU0_PH5_PHASE")
		)
		(pad "33" smd rect
			(at 0.700024 -2.895092 90)
			(size 0.254 0.7112)
			(layers "F.Cu" "F.Mask" "F.Paste")
			(net "VR_PVCCIN_CPU0_PH5_BOOT_R")
		)
		(pad "34" smd rect
			(at 0.249936 -2.895092 90)
			(size 0.254 0.7112)
			(layers "F.Cu" "F.Mask" "F.Paste")
			(net "VR_PVCCIN_CPU0_PWM5")
		)
		(pad "35" smd rect
			(at -0.199898 -2.895092 90)
			(size 0.254 0.7112)
			(layers "F.Cu" "F.Mask" "F.Paste")
			(net "P5V_STBY")
		)
		(pad "36" smd rect
			(at -0.649986 -2.895092 90)
			(size 0.254 0.7112)
			(layers "F.Cu" "F.Mask" "F.Paste")
			(net "A_TSENSE_PVCCIN_CPU0")
		)
		(pad "37" smd rect
			(at -1.100074 -2.895092 90)
			(size 0.254 0.7112)
			(layers "F.Cu" "F.Mask" "F.Paste")
			(net "VR_PVCCIN_CPU0_PH5_OCSET")
		)
		(pad "38" smd rect
			(at -1.549908 -2.895092 90)
			(size 0.254 0.7112)
			(layers "F.Cu" "F.Mask" "F.Paste")
			(net "ISENSE_PVCCIN_CPU0_PH5_IMON")
		)
		(pad "39" smd rect
			(at -1.999996 -2.895092 90)
			(size 0.254 0.7112)
			(layers "F.Cu" "F.Mask" "F.Paste")
			(net "VR_PVCCIN_CPU0_AIREF5")
		)
		(pad "40" smd rect
			(at -0.871728 -1.283208 90)
			(size 1.8034 2.0066)
			(layers "F.Cu" "F.Mask" "F.Paste")
			(net "GND")
		)
		(pad "41" smd rect
			(at -1.533906 0.247904 90)
			(size 0.508 0.3556)
			(layers "F.Cu" "F.Mask" "F.Paste")
			(net "TP_PVCCIN_CPU0_PH5_GL_1")
		)
	)
)
